# SCM (Grand Teton) — schematic netlist excerpt (pin names and nets, part order shuffled) for the footprints in the layout excerpt that follows; sources: Cadence DE-HDL packaged netlist, KiCad conversion of 12092022_DA0F0TMDCD0_F0T_Management_Board_D_brd_V3_OCP.brd

R788  Q_RES  2K 1% CHIP  pkg 0402LF  page 15 : A = P5V_SENSOR ; B = GND
R544  Q_RES  0 5% CHIP  pkg 0402LF  page 31 : A = UART_SYS_DBG_TX ; B = UART_SYS_DBG_TX_R

(kicad_pcb
	(version 20260206)
	(generator "pcbnew")
	(generator_version "10.0")
	(general
		(thickness 1.6)
		(legacy_teardrops no)
	)
	(paper "A4")
	(title_block
		(title "12092022_DA0F0TMDCD0_F0T_Management_Board_D_brd_V3_OCP.brd")
		(comment 1 "Grand Teton / footprints 873-874 of 1440")
	)
	(layers
		(0 "F.Cu" signal "TOP")
		(4 "In1.Cu" signal "GND")
		(6 "In2.Cu" signal "IN1")
		(8 "In3.Cu" signal "GND1")
		(10 "In4.Cu" signal "IN2")
		(12 "In5.Cu" signal "VCC")
		(14 "In6.Cu" signal "VCC1")
		(16 "In7.Cu" signal "IN3")
		(18 "In8.Cu" signal "GND2")
		(20 "In9.Cu" signal "IN4")
		(22 "In10.Cu" signal "GND3")
		(2 "B.Cu" signal "BOTTOM")
		(9 "F.Adhes" user "F.Adhesive")
		(11 "B.Adhes" user "B.Adhesive")
		(13 "F.Paste" user "Package Geometry/Pastemask Top")
		(15 "B.Paste" user "Package Geometry/Pastemask Bottom")
		(5 "F.SilkS" user "Ref Des/Silkscreen Top")
		(7 "B.SilkS" user "Ref Des/Silkscreen Bottom")
		(1 "F.Mask" user "Board Geometry/Soldermask Top")
		(3 "B.Mask" user "Board Geometry/Soldermask Bottom")
		(17 "Dwgs.User" user "User.Drawings")
		(19 "Cmts.User" user "User.Comments")
		(21 "Eco1.User" user "User.Eco1")
		(23 "Eco2.User" user "User.Eco2")
		(25 "Edge.Cuts" user "Board Geometry/Outline")
		(27 "Margin" user)
		(31 "F.CrtYd" user "Package Geometry/Place Bound Top")
		(29 "B.CrtYd" user "Package Geometry/Place Bound Bottom")
		(35 "F.Fab" user "Ref Des/Assembly Top")
		(33 "B.Fab" user "Ref Des/Assembly Bottom")
	)
	(footprint ""
		(layer "B.Cu")
		(at 28.9306 -63.4746 180)
		(property "Reference" "R544"
			(at 0 0 0)
			(layer "B.SilkS")
			(hide yes)
			(effects
				(font
					(size 1.27 1.27)
				)
				(justify mirror)
			)
		)
		(property "Value" ""
			(at 0 0 0)
			(layer "B.Fab")
			(effects
				(font
					(size 1.27 1.27)
				)
				(justify mirror)
			)
		)
		(duplicate_pad_numbers_are_jumpers no)
		(fp_line
			(start 0.7874 0.4064)
			(end 0.7874 -0.4064)
			(stroke
				(width 0.1524)
				(type default)
			)
			(layer "B.SilkS")
		)
		(fp_line
			(start 0.7874 -0.4064)
			(end -0.7874 -0.4064)
			(stroke
				(width 0.1524)
				(type default)
			)
			(layer "B.SilkS")
		)
		(fp_line
			(start -0.7874 0.4064)
			(end 0.7874 0.4064)
			(stroke
				(width 0.1524)
				(type default)
			)
			(layer "B.SilkS")
		)
		(fp_line
			(start -0.7874 -0.4064)
			(end -0.7874 0.4064)
			(stroke
				(width 0.1524)
				(type default)
			)
			(layer "B.SilkS")
		)
		(fp_line
			(start 0.67945 0.3048)
			(end 0.67945 -0.305054)
			(stroke
				(width 0.1)
				(type default)
			)
			(layer "B.Fab")
		)
		(fp_line
			(start 0.67945 -0.305054)
			(end 0.12065 -0.305054)
			(stroke
				(width 0.1)
				(type default)
			)
			(layer "B.Fab")
		)
		(fp_line
			(start 0.12065 0.3048)
			(end 0.67945 0.3048)
			(stroke
				(width 0.1)
				(type default)
			)
			(layer "B.Fab")
		)
		(fp_line
			(start 0.12065 0.2794)
			(end 0.12065 0.3048)
			(stroke
				(width 0.1)
				(type default)
			)
			(layer "B.Fab")
		)
		(fp_line
			(start 0.12065 -0.2794)
			(end -0.12065 -0.2794)
			(stroke
				(width 0.1)
				(type default)
			)
			(layer "B.Fab")
		)
		(fp_line
			(start 0.12065 -0.305054)
			(end 0.12065 -0.2794)
			(stroke
				(width 0.1)
				(type default)
			)
			(layer "B.Fab")
		)
		(fp_line
			(start -0.120396 0.3048)
			(end -0.120396 0.2794)
			(stroke
				(width 0.1)
				(type default)
			)
			(layer "B.Fab")
		)
		(fp_line
			(start -0.120396 0.2794)
			(end 0.12065 0.2794)
			(stroke
				(width 0.1)
				(type default)
			)
			(layer "B.Fab")
		)
		(fp_line
			(start -0.12065 -0.2794)
			(end -0.12065 -0.3048)
			(stroke
				(width 0.1)
				(type default)
			)
			(layer "B.Fab")
		)
		(fp_line
			(start -0.12065 -0.3048)
			(end -0.67945 -0.3048)
			(stroke
				(width 0.1)
				(type default)
			)
			(layer "B.Fab")
		)
		(fp_line
			(start -0.67945 0.3048)
			(end -0.120396 0.3048)
			(stroke
				(width 0.1)
				(type default)
			)
			(layer "B.Fab")
		)
		(fp_line
			(start -0.67945 -0.3048)
			(end -0.67945 0.3048)
			(stroke
				(width 0.1)
				(type default)
			)
			(layer "B.Fab")
		)
		(pad "1" smd circle
			(at 0.40005 0)
			(size 0 0)
			(layers "B.Cu" "B.Mask" "B.Paste")
			(net "UART_SYS_DBG_TX")
		)
		(pad "2" smd circle
			(at -0.40005 0)
			(size 0 0)
			(layers "B.Cu" "B.Mask" "B.Paste")
			(net "UART_SYS_DBG_TX_R")
		)
	)
	(footprint ""
		(layer "B.Cu")
		(at 57.884822 -72.621648)
		(property "Reference" "R788"
			(at 0 0 0)
			(layer "B.SilkS")
			(hide yes)
			(effects
				(font
					(size 1.27 1.27)
				)
				(justify mirror)
			)
		)
		(property "Value" ""
			(at 0 0 0)
			(layer "B.Fab")
			(effects
				(font
					(size 1.27 1.27)
				)
				(justify mirror)
			)
		)
		(duplicate_pad_numbers_are_jumpers no)
		(fp_line
			(start -0.7874 -0.4064)
			(end -0.7874 0.4064)
			(stroke
				(width 0.1524)
				(type default)
			)
			(layer "B.SilkS")
		)
		(fp_line
			(start -0.7874 0.4064)
			(end 0.7874 0.4064)
			(stroke
				(width 0.1524)
				(type default)
			)
			(layer "B.SilkS")
		)
		(fp_line
			(start 0.7874 -0.4064)
			(end -0.7874 -0.4064)
			(stroke
				(width 0.1524)
				(type default)
			)
			(layer "B.SilkS")
		)
		(fp_line
			(start 0.7874 0.4064)
			(end 0.7874 -0.4064)
			(stroke
				(width 0.1524)
				(type default)
			)
			(layer "B.SilkS")
		)
		(fp_line
			(start -0.67945 -0.3048)
			(end -0.67945 0.3048)
			(stroke
				(width 0.1)
				(type default)
			)
			(layer "B.Fab")
		)
		(fp_line
			(start -0.67945 0.3048)
			(end -0.120396 0.3048)
			(stroke
				(width 0.1)
				(type default)
			)
			(layer "B.Fab")
		)
		(fp_line
			(start -0.12065 -0.3048)
			(end -0.67945 -0.3048)
			(stroke
				(width 0.1)
				(type default)
			)
			(layer "B.Fab")
		)
		(fp_line
			(start -0.12065 -0.2794)
			(end -0.12065 -0.3048)
			(stroke
				(width 0.1)
				(type default)
			)
			(layer "B.Fab")
		)
		(fp_line
			(start -0.120396 0.2794)
			(end 0.12065 0.2794)
			(stroke
				(width 0.1)
				(type default)
			)
			(layer "B.Fab")
		)
		(fp_line
			(start -0.120396 0.3048)
			(end -0.120396 0.2794)
			(stroke
				(width 0.1)
				(type default)
			)
			(layer "B.Fab")
		)
		(fp_line
			(start 0.12065 -0.305054)
			(end 0.12065 -0.2794)
			(stroke
				(width 0.1)
				(type default)
			)
			(layer "B.Fab")
		)
		(fp_line
			(start 0.12065 -0.2794)
			(end -0.12065 -0.2794)
			(stroke
				(width 0.1)
				(type default)
			)
			(layer "B.Fab")
		)
		(fp_line
			(start 0.12065 0.2794)
			(end 0.12065 0.3048)
			(stroke
				(width 0.1)
				(type default)
			)
			(layer "B.Fab")
		)
		(fp_line
			(start 0.12065 0.3048)
			(end 0.67945 0.3048)
			(stroke
				(width 0.1)
				(type default)
			)
			(layer "B.Fab")
		)
		(fp_line
			(start 0.67945 -0.305054)
			(end 0.12065 -0.305054)
			(stroke
				(width 0.1)
				(type default)
			)
			(layer "B.Fab")
		)
		(fp_line
			(start 0.67945 0.3048)
			(end 0.67945 -0.305054)
			(stroke
				(width 0.1)
				(type default)
			)
			(layer "B.Fab")
		)
		(pad "1" smd circle
			(at 0.40005 0 180)
			(size 0 0)
			(layers "B.Cu" "B.Mask" "B.Paste")
			(net "P5V_SENSOR")
		)
		(pad "2" smd circle
			(at -0.40005 0 180)
			(size 0 0)
			(layers "B.Cu" "B.Mask" "B.Paste")
			(net "GND")
		)
	)
)
